# SCM (Grand Teton) — schematic netlist excerpt (pin names and nets, part order shuffled) for the footprints in the layout excerpt that follows; sources: Cadence DE-HDL packaged netlist, KiCad conversion of 12092022_DA0F0TMDCD0_F0T_Management_Board_D_brd_V3_OCP.brd

R527  Q_RES  0 5% CHIP  pkg 0402LF  page 15 : A = USB_HOST_BMC_B_R_DP ; B = USB_HOST_BMC_B_DP
R200  Q_RES  110 1% CHIP  pkg 0402LF  page 14 : A = I3C4_SCL_R ; B = I3C4_SPD_SCL

(kicad_pcb
	(version 20260206)
	(generator "pcbnew")
	(generator_version "10.0")
	(general
		(thickness 1.6)
		(legacy_teardrops no)
	)
	(paper "A4")
	(title_block
		(title "12092022_DA0F0TMDCD0_F0T_Management_Board_D_brd_V3_OCP.brd")
		(comment 1 "Grand Teton / footprints 541-542 of 1440")
	)
	(layers
		(0 "F.Cu" signal "TOP")
		(4 "In1.Cu" signal "GND")
		(6 "In2.Cu" signal "IN1")
		(8 "In3.Cu" signal "GND1")
		(10 "In4.Cu" signal "IN2")
		(12 "In5.Cu" signal "VCC")
		(14 "In6.Cu" signal "VCC1")
		(16 "In7.Cu" signal "IN3")
		(18 "In8.Cu" signal "GND2")
		(20 "In9.Cu" signal "IN4")
		(22 "In10.Cu" signal "GND3")
		(2 "B.Cu" signal "BOTTOM")
		(9 "F.Adhes" user "F.Adhesive")
		(11 "B.Adhes" user "B.Adhesive")
		(13 "F.Paste" user "Package Geometry/Pastemask Top")
		(15 "B.Paste" user "Package Geometry/Pastemask Bottom")
		(5 "F.SilkS" user "Ref Des/Silkscreen Top")
		(7 "B.SilkS" user "Ref Des/Silkscreen Bottom")
		(1 "F.Mask" user "Board Geometry/Soldermask Top")
		(3 "B.Mask" user "Board Geometry/Soldermask Bottom")
		(17 "Dwgs.User" user "User.Drawings")
		(19 "Cmts.User" user "User.Comments")
		(21 "Eco1.User" user "User.Eco1")
		(23 "Eco2.User" user "User.Eco2")
		(25 "Edge.Cuts" user "Board Geometry/Outline")
		(27 "Margin" user)
		(31 "F.CrtYd" user "Package Geometry/Place Bound Top")
		(29 "B.CrtYd" user "Package Geometry/Place Bound Bottom")
		(35 "F.Fab" user "Ref Des/Assembly Top")
		(33 "B.Fab" user "Ref Des/Assembly Bottom")
	)
	(footprint ""
		(layer "F.Cu")
		(at 39.871142 -63.756794 90)
		(property "Reference" "R200"
			(at 0 0 90)
			(layer "F.SilkS")
			(hide yes)
			(effects
				(font
					(size 1.27 1.27)
				)
			)
		)
		(property "Value" ""
			(at 0 0 90)
			(layer "F.Fab")
			(effects
				(font
					(size 1.27 1.27)
				)
			)
		)
		(duplicate_pad_numbers_are_jumpers no)
		(fp_line
			(start 0.7874 -0.4064)
			(end 0.7874 0.4064)
			(stroke
				(width 0.1524)
				(type default)
			)
			(layer "F.SilkS")
		)
		(fp_line
			(start -0.7874 -0.4064)
			(end 0.7874 -0.4064)
			(stroke
				(width 0.1524)
				(type default)
			)
			(layer "F.SilkS")
		)
		(fp_line
			(start 0.7874 0.4064)
			(end -0.7874 0.4064)
			(stroke
				(width 0.1524)
				(type default)
			)
			(layer "F.SilkS")
		)
		(fp_line
			(start -0.7874 0.4064)
			(end -0.7874 -0.4064)
			(stroke
				(width 0.1524)
				(type default)
			)
			(layer "F.SilkS")
		)
		(fp_line
			(start -0.12065 -0.305054)
			(end -0.12065 -0.2794)
			(stroke
				(width 0.1)
				(type default)
			)
			(layer "F.Fab")
		)
		(fp_line
			(start -0.67945 -0.305054)
			(end -0.12065 -0.305054)
			(stroke
				(width 0.1)
				(type default)
			)
			(layer "F.Fab")
		)
		(fp_line
			(start 0.67945 -0.3048)
			(end 0.67945 0.3048)
			(stroke
				(width 0.1)
				(type default)
			)
			(layer "F.Fab")
		)
		(fp_line
			(start 0.12065 -0.3048)
			(end 0.67945 -0.3048)
			(stroke
				(width 0.1)
				(type default)
			)
			(layer "F.Fab")
		)
		(fp_line
			(start 0.12065 -0.2794)
			(end 0.12065 -0.3048)
			(stroke
				(width 0.1)
				(type default)
			)
			(layer "F.Fab")
		)
		(fp_line
			(start -0.12065 -0.2794)
			(end 0.12065 -0.2794)
			(stroke
				(width 0.1)
				(type default)
			)
			(layer "F.Fab")
		)
		(fp_line
			(start 0.120396 0.2794)
			(end -0.12065 0.2794)
			(stroke
				(width 0.1)
				(type default)
			)
			(layer "F.Fab")
		)
		(fp_line
			(start -0.12065 0.2794)
			(end -0.12065 0.3048)
			(stroke
				(width 0.1)
				(type default)
			)
			(layer "F.Fab")
		)
		(fp_line
			(start 0.67945 0.3048)
			(end 0.120396 0.3048)
			(stroke
				(width 0.1)
				(type default)
			)
			(layer "F.Fab")
		)
		(fp_line
			(start 0.120396 0.3048)
			(end 0.120396 0.2794)
			(stroke
				(width 0.1)
				(type default)
			)
			(layer "F.Fab")
		)
		(fp_line
			(start -0.12065 0.3048)
			(end -0.67945 0.3048)
			(stroke
				(width 0.1)
				(type default)
			)
			(layer "F.Fab")
		)
		(fp_line
			(start -0.67945 0.3048)
			(end -0.67945 -0.305054)
			(stroke
				(width 0.1)
				(type default)
			)
			(layer "F.Fab")
		)
		(pad "1" smd circle
			(at -0.40005 0 90)
			(size 0 0)
			(layers "F.Cu" "F.Mask" "F.Paste")
			(net "I3C4_SCL_R")
		)
		(pad "2" smd circle
			(at 0.40005 0 90)
			(size 0 0)
			(layers "F.Cu" "F.Mask" "F.Paste")
			(net "I3C4_SPD_SCL")
		)
	)
	(footprint ""
		(layer "F.Cu")
		(at 62.53607 -34.870898 -90)
		(property "Reference" "R527"
			(at 0 0 270)
			(layer "F.SilkS")
			(hide yes)
			(effects
				(font
					(size 1.27 1.27)
				)
			)
		)
		(property "Value" ""
			(at 0 0 270)
			(layer "F.Fab")
			(effects
				(font
					(size 1.27 1.27)
				)
			)
		)
		(duplicate_pad_numbers_are_jumpers no)
		(fp_line
			(start -0.7874 0.4064)
			(end -0.7874 -0.14097)
			(stroke
				(width 0.1524)
				(type default)
			)
			(layer "F.SilkS")
		)
		(fp_line
			(start 0.7874 0.4064)
			(end -0.7874 0.4064)
			(stroke
				(width 0.1524)
				(type default)
			)
			(layer "F.SilkS")
		)
		(fp_line
			(start 0.7874 -0.04191)
			(end 0.7874 0.4064)
			(stroke
				(width 0.1524)
				(type default)
			)
			(layer "F.SilkS")
		)
		(fp_line
			(start -0.054102 -0.4064)
			(end 0.420878 -0.4064)
			(stroke
				(width 0.1524)
				(type default)
			)
			(layer "F.SilkS")
		)
		(fp_line
			(start -0.67945 0.3048)
			(end -0.67945 -0.305054)
			(stroke
				(width 0.1)
				(type default)
			)
			(layer "F.Fab")
		)
		(fp_line
			(start -0.12065 0.3048)
			(end -0.67945 0.3048)
			(stroke
				(width 0.1)
				(type default)
			)
			(layer "F.Fab")
		)
		(fp_line
			(start 0.120396 0.3048)
			(end 0.120396 0.2794)
			(stroke
				(width 0.1)
				(type default)
			)
			(layer "F.Fab")
		)
		(fp_line
			(start 0.67945 0.3048)
			(end 0.120396 0.3048)
			(stroke
				(width 0.1)
				(type default)
			)
			(layer "F.Fab")
		)
		(fp_line
			(start -0.12065 0.2794)
			(end -0.12065 0.3048)
			(stroke
				(width 0.1)
				(type default)
			)
			(layer "F.Fab")
		)
		(fp_line
			(start 0.120396 0.2794)
			(end -0.12065 0.2794)
			(stroke
				(width 0.1)
				(type default)
			)
			(layer "F.Fab")
		)
		(fp_line
			(start -0.12065 -0.2794)
			(end 0.12065 -0.2794)
			(stroke
				(width 0.1)
				(type default)
			)
			(layer "F.Fab")
		)
		(fp_line
			(start 0.12065 -0.2794)
			(end 0.12065 -0.3048)
			(stroke
				(width 0.1)
				(type default)
			)
			(layer "F.Fab")
		)
		(fp_line
			(start 0.12065 -0.3048)
			(end 0.67945 -0.3048)
			(stroke
				(width 0.1)
				(type default)
			)
			(layer "F.Fab")
		)
		(fp_line
			(start 0.67945 -0.3048)
			(end 0.67945 0.3048)
			(stroke
				(width 0.1)
				(type default)
			)
			(layer "F.Fab")
		)
		(fp_line
			(start -0.67945 -0.305054)
			(end -0.12065 -0.305054)
			(stroke
				(width 0.1)
				(type default)
			)
			(layer "F.Fab")
		)
		(fp_line
			(start -0.12065 -0.305054)
			(end -0.12065 -0.2794)
			(stroke
				(width 0.1)
				(type default)
			)
			(layer "F.Fab")
		)
		(pad "1" smd circle
			(at -0.40005 0 270)
			(size 0 0)
			(layers "F.Cu" "F.Mask" "F.Paste")
			(net "USB_HOST_BMC_B_R_DP")
		)
		(pad "2" smd circle
			(at 0.40005 0 270)
			(size 0 0)
			(layers "F.Cu" "F.Mask" "F.Paste")
			(net "USB_HOST_BMC_B_DP")
		)
	)
)
